#ISCELL
  mstr_misc dns *
  *
#ISCELL
  pure_quanta quanta_title_block_c *
  *
#ISCELL
  pure_quanta_power universal_gnd *
  page166_i10
#ISCELL
  pure_quanta_power universal_gnd *
  page166_i12
#ISCELL
  pure_quanta_power universal_gnd *
  page166_i14
#CELL
  pure_quanta q_cap *
  page166_i15
#CELL
  pure_quanta q_cap *
  page166_i16
#ISCELL
  pure_quanta_power universal_gnd *
  page166_i17
#CELL
  pure_quanta q_cap *
  page166_i18
#ISCELL
  pure_quanta_power vcc_core *
  page166_i19
#ISCELL
  standard offpage *
  page166_i2
#ISCELL
  pure_quanta_power vcc_core *
  page166_i20
#CELL
  pure_quanta q_res *
  page166_i21
#CELL
  pure_quanta q_res *
  page166_i22
#ISCELL
  pure_quanta_power universal_gnd *
  page166_i23
#CELL
  pure_quanta q_cap *
  page166_i24
#CELL
  pure_quanta q_res *
  page166_i25
#ISCELL
  standard offpage *
  page166_i26
#ISCELL
  pure_quanta_power vcc_core *
  page166_i3
#CELL
  pure_quanta rt9059gqw *
  page166_i4
#CELL
  pure_quanta q_res *
  page166_i6
#ISCELL
  pure_quanta_power universal_gnd *
  page166_i7
#CELL
  pure_quanta q_cap *
  page166_i8
#ISCELL
  pure_quanta_power vcc_core *
  page166_i9
